# T6G (Grand Teton) — schematic netlist excerpt (pin names and nets, part order shuffled) for the footprints in the layout excerpt that follows; sources: Cadence DE-HDL packaged netlist, KiCad conversion of 04192023_DAF0TMB3IC0_F0TG_MB_C_brd_V02_OCP.brd

R1738  Q_RES  0 5% CHIP  pkg 0402LF  page 171 : A = JTAG_SCM_MUX_R_TDI ; B = JTAG_SCM_MUX_TDI
R3183  Q_RES  10K 1% CHIP  pkg 0402LF  page 139 : A = P3V3_OCP_V3_2 ; B = PU_OCP_V3_2_WAKE_OE

(kicad_pcb
	(version 20260206)
	(generator "pcbnew")
	(generator_version "10.0")
	(general
		(thickness 1.6)
		(legacy_teardrops no)
	)
	(paper "A4")
	(title_block
		(title "04192023_DAF0TMB3IC0_F0TG_MB_C_brd_V02_OCP.brd")
		(comment 1 "Grand Teton / footprints 4256-4257 of 8354")
	)
	(layers
		(0 "F.Cu" signal "TOP")
		(4 "In1.Cu" signal "GND")
		(6 "In2.Cu" signal "IN1")
		(8 "In3.Cu" signal "GND1")
		(10 "In4.Cu" signal "IN2")
		(12 "In5.Cu" signal "GND2")
		(14 "In6.Cu" signal "IN3")
		(16 "In7.Cu" signal "GND3")
		(18 "In8.Cu" signal "VCC")
		(20 "In9.Cu" signal "VCC1")
		(22 "In10.Cu" signal "GND4")
		(24 "In11.Cu" signal "IN4")
		(26 "In12.Cu" signal "GND5")
		(28 "In13.Cu" signal "IN5")
		(30 "In14.Cu" signal "GND6")
		(32 "In15.Cu" signal "IN6")
		(34 "In16.Cu" signal "GND7")
		(2 "B.Cu" signal "BOTTOM")
		(9 "F.Adhes" user "F.Adhesive")
		(11 "B.Adhes" user "B.Adhesive")
		(13 "F.Paste" user "Package Geometry/Pastemask Top")
		(15 "B.Paste" user "Package Geometry/Pastemask Bottom")
		(5 "F.SilkS" user "Ref Des/Silkscreen Top")
		(7 "B.SilkS" user "Ref Des/Silkscreen Bottom")
		(1 "F.Mask" user "Board Geometry/Soldermask Top")
		(3 "B.Mask" user "Board Geometry/Soldermask Bottom")
		(17 "Dwgs.User" user "User.Drawings")
		(19 "Cmts.User" user "User.Comments")
		(21 "Eco1.User" user "User.Eco1")
		(23 "Eco2.User" user "User.Eco2")
		(25 "Edge.Cuts" user "Board Geometry/Outline")
		(27 "Margin" user)
		(31 "F.CrtYd" user "Package Geometry/Place Bound Top")
		(29 "B.CrtYd" user "Package Geometry/Place Bound Bottom")
		(35 "F.Fab" user "Ref Des/Assembly Top")
		(33 "B.Fab" user "Ref Des/Assembly Bottom")
	)
	(footprint ""
		(layer "F.Cu")
		(at 102.563422 -38.678612 180)
		(property "Reference" "R3183"
			(at 0 0 180)
			(layer "F.SilkS")
			(hide yes)
			(effects
				(font
					(size 1.27 1.27)
				)
			)
		)
		(property "Value" ""
			(at 0 0 180)
			(layer "F.Fab")
			(effects
				(font
					(size 1.27 1.27)
				)
			)
		)
		(duplicate_pad_numbers_are_jumpers no)
		(fp_line
			(start 0.7874 0.4064)
			(end -0.7874 0.4064)
			(stroke
				(width 0.1524)
				(type default)
			)
			(layer "F.SilkS")
		)
		(fp_line
			(start 0.7874 -0.4064)
			(end 0.7874 0.4064)
			(stroke
				(width 0.1524)
				(type default)
			)
			(layer "F.SilkS")
		)
		(fp_line
			(start -0.7874 0.4064)
			(end -0.7874 -0.4064)
			(stroke
				(width 0.1524)
				(type default)
			)
			(layer "F.SilkS")
		)
		(fp_line
			(start -0.7874 -0.4064)
			(end 0.7874 -0.4064)
			(stroke
				(width 0.1524)
				(type default)
			)
			(layer "F.SilkS")
		)
		(fp_line
			(start 0.67945 0.3048)
			(end 0.120396 0.3048)
			(stroke
				(width 0.1)
				(type default)
			)
			(layer "F.Fab")
		)
		(fp_line
			(start 0.67945 -0.3048)
			(end 0.67945 0.3048)
			(stroke
				(width 0.1)
				(type default)
			)
			(layer "F.Fab")
		)
		(fp_line
			(start 0.12065 -0.2794)
			(end 0.12065 -0.3048)
			(stroke
				(width 0.1)
				(type default)
			)
			(layer "F.Fab")
		)
		(fp_line
			(start 0.12065 -0.3048)
			(end 0.67945 -0.3048)
			(stroke
				(width 0.1)
				(type default)
			)
			(layer "F.Fab")
		)
		(fp_line
			(start 0.120396 0.3048)
			(end 0.120396 0.2794)
			(stroke
				(width 0.1)
				(type default)
			)
			(layer "F.Fab")
		)
		(fp_line
			(start 0.120396 0.2794)
			(end -0.12065 0.2794)
			(stroke
				(width 0.1)
				(type default)
			)
			(layer "F.Fab")
		)
		(fp_line
			(start -0.12065 0.3048)
			(end -0.67945 0.3048)
			(stroke
				(width 0.1)
				(type default)
			)
			(layer "F.Fab")
		)
		(fp_line
			(start -0.12065 0.2794)
			(end -0.12065 0.3048)
			(stroke
				(width 0.1)
				(type default)
			)
			(layer "F.Fab")
		)
		(fp_line
			(start -0.12065 -0.2794)
			(end 0.12065 -0.2794)
			(stroke
				(width 0.1)
				(type default)
			)
			(layer "F.Fab")
		)
		(fp_line
			(start -0.12065 -0.305054)
			(end -0.12065 -0.2794)
			(stroke
				(width 0.1)
				(type default)
			)
			(layer "F.Fab")
		)
		(fp_line
			(start -0.67945 0.3048)
			(end -0.67945 -0.305054)
			(stroke
				(width 0.1)
				(type default)
			)
			(layer "F.Fab")
		)
		(fp_line
			(start -0.67945 -0.305054)
			(end -0.12065 -0.305054)
			(stroke
				(width 0.1)
				(type default)
			)
			(layer "F.Fab")
		)
		(pad "1" smd circle
			(at -0.40005 0 180)
			(size 0 0)
			(layers "F.Cu" "F.Mask" "F.Paste")
			(net "P3V3_OCP_V3_2")
		)
		(pad "2" smd circle
			(at 0.40005 0 180)
			(size 0 0)
			(layers "F.Cu" "F.Mask" "F.Paste")
			(net "PU_OCP_V3_2_WAKE_OE")
		)
	)
	(footprint ""
		(layer "F.Cu")
		(at 138.426952 -60.849764)
		(property "Reference" "R1738"
			(at 0 0 0)
			(layer "F.SilkS")
			(hide yes)
			(effects
				(font
					(size 1.27 1.27)
				)
			)
		)
		(property "Value" ""
			(at 0 0 0)
			(layer "F.Fab")
			(effects
				(font
					(size 1.27 1.27)
				)
			)
		)
		(duplicate_pad_numbers_are_jumpers no)
		(fp_line
			(start -0.7874 -0.4064)
			(end 0.7874 -0.4064)
			(stroke
				(width 0.1524)
				(type default)
			)
			(layer "F.SilkS")
		)
		(fp_line
			(start -0.7874 0.4064)
			(end -0.7874 -0.4064)
			(stroke
				(width 0.1524)
				(type default)
			)
			(layer "F.SilkS")
		)
		(fp_line
			(start 0.7874 -0.4064)
			(end 0.7874 0.4064)
			(stroke
				(width 0.1524)
				(type default)
			)
			(layer "F.SilkS")
		)
		(fp_line
			(start 0.7874 0.4064)
			(end -0.7874 0.4064)
			(stroke
				(width 0.1524)
				(type default)
			)
			(layer "F.SilkS")
		)
		(fp_line
			(start -0.67945 -0.305054)
			(end -0.12065 -0.305054)
			(stroke
				(width 0.1)
				(type default)
			)
			(layer "F.Fab")
		)
		(fp_line
			(start -0.67945 0.3048)
			(end -0.67945 -0.305054)
			(stroke
				(width 0.1)
				(type default)
			)
			(layer "F.Fab")
		)
		(fp_line
			(start -0.12065 -0.305054)
			(end -0.12065 -0.2794)
			(stroke
				(width 0.1)
				(type default)
			)
			(layer "F.Fab")
		)
		(fp_line
			(start -0.12065 -0.2794)
			(end 0.12065 -0.2794)
			(stroke
				(width 0.1)
				(type default)
			)
			(layer "F.Fab")
		)
		(fp_line
			(start -0.12065 0.2794)
			(end -0.12065 0.3048)
			(stroke
				(width 0.1)
				(type default)
			)
			(layer "F.Fab")
		)
		(fp_line
			(start -0.12065 0.3048)
			(end -0.67945 0.3048)
			(stroke
				(width 0.1)
				(type default)
			)
			(layer "F.Fab")
		)
		(fp_line
			(start 0.120396 0.2794)
			(end -0.12065 0.2794)
			(stroke
				(width 0.1)
				(type default)
			)
			(layer "F.Fab")
		)
		(fp_line
			(start 0.120396 0.3048)
			(end 0.120396 0.2794)
			(stroke
				(width 0.1)
				(type default)
			)
			(layer "F.Fab")
		)
		(fp_line
			(start 0.12065 -0.3048)
			(end 0.67945 -0.3048)
			(stroke
				(width 0.1)
				(type default)
			)
			(layer "F.Fab")
		)
		(fp_line
			(start 0.12065 -0.2794)
			(end 0.12065 -0.3048)
			(stroke
				(width 0.1)
				(type default)
			)
			(layer "F.Fab")
		)
		(fp_line
			(start 0.67945 -0.3048)
			(end 0.67945 0.3048)
			(stroke
				(width 0.1)
				(type default)
			)
			(layer "F.Fab")
		)
		(fp_line
			(start 0.67945 0.3048)
			(end 0.120396 0.3048)
			(stroke
				(width 0.1)
				(type default)
			)
			(layer "F.Fab")
		)
		(pad "1" smd circle
			(at -0.40005 0)
			(size 0 0)
			(layers "F.Cu" "F.Mask" "F.Paste")
			(net "JTAG_SCM_MUX_R_TDI")
		)
		(pad "2" smd circle
			(at 0.40005 0)
			(size 0 0)
			(layers "F.Cu" "F.Mask" "F.Paste")
			(net "JTAG_SCM_MUX_TDI")
		)
	)
)
